FILE_TYPE = CONNECTIVITY;
{Allegro Design Entry HDL 16.6-p007 (v16-6-112F) 10/10/2012}
"PAGE_NUMBER" = 29;
0"NC";
1"DMI_CPU0_PCH_TX_DN<3:0>";
2"DMI_CPU0_PCH_TX_DP<3:0>";
3"DMI_CPU0_PCH_RX_C_DN<3:0>";
4"DMI_CPU0_PCH_RX_C_DP<3:0>";
5"PVCCMCP_CPU0\g";
6"TP_CPU0_RSVD_174";
7"TP_CPU0_RSVD_175";
8"TP_CPU0_RSVD_176";
9"TP_CPU0_RSVD_177";
10"TP_CPU0_RSVD_178";
11"TP_CPU0_RSVD_181";
12"TP_CPU0_RSVD_179";
13"TP_CPU0_RSVD_180";
14"DMI_CPU0_PCH_RX_C_DP<0>";
15"DMI_CPU0_PCH_RX_C_DP<1>";
16"DMI_CPU0_PCH_RX_C_DP<2>";
17"DMI_CPU0_PCH_RX_C_DP<3>";
18"DMI_CPU0_PCH_RX_C_DN<0>";
19"DMI_CPU0_PCH_RX_C_DN<1>";
20"DMI_CPU0_PCH_RX_C_DN<2>";
21"DMI_CPU0_PCH_RX_C_DN<3>";
22"TP_CPU0_RSVD_182";
23"TP_CPU0_RSVD_183";
24"JTAG_MCP_TCK";
25"JTAG_MCP_CPU0_TDI";
26"JTAG_MCP_TMS";
27"CLK_156M_OSC_CPU0_HFI_DP";
28"CLK_156M_OSC_CPU0_HFI_DN";
29"RST_HFI0_CPU0_LVT2_N";
30"FM_MODPRST_HFI0_CPU0_LVT2_N";
31"IRQ_HFI0_CPU0_LVT2_N";
32"LED_HFI0_CPU0_N";
33"SMB_HFI0_CPU0_LVC2_SCL";
34"SMB_HFI0_CPU0_LVC2_SDA";
35"JTAG_MCP_TRST_N";
36"TP_CPU0_RSVD_172";
37"TP_CPU0_RSVD_173";
38"TP_CPU0_RSVD_184";
39"TP_CPU0_RSVD_186";
40"TP_CPU0_RSVD_189";
41"TP_CPU0_RSVD_190";
42"DMI_CPU0_PCH_TX_DN<0>";
43"DMI_CPU0_PCH_TX_DP<0>";
44"DMI_CPU0_PCH_TX_DP<1>";
45"DMI_CPU0_PCH_TX_DP<2>";
46"DMI_CPU0_PCH_TX_DP<3>";
47"DMI_CPU0_PCH_TX_DN<1>";
48"DMI_CPU0_PCH_TX_DN<2>";
49"DMI_CPU0_PCH_TX_DN<3>";
50"JTAG_MCP_CPU0_TDO";
51"CLK_100M_CPU0_PE_REFCLK_DP";
52"CLK_100M_CPU0_PE_REFCLK_DN";
53"RST_CD_CPU0_POR_N";
54"FM_MODPRST_HFI1_CPU0_LVT2_N";
55"IRQ_HFI1_CPU0_LVT2_N";
56"RST_HFI1_CPU0_LVT2_N";
57"LED_HFI1_CPU0_N";
58"SMB_HFI1_CPU0_LVC2_SCL";
59"SMB_HFI1_CPU0_LVC2_SDA";
%"TAP"
"1","(-5425,3150)","2","mstr_standard","I10";
;
HDL_TAP"TRUE"
BODY_TYPE"PLUMBING"
CDS_LIB"mstr_standard";
"B \NAC \NWC"3;
"S \NAC"
BN"2"20;
%"TAP"
"1","(-5425,3300)","2","mstr_standard","I11";
;
HDL_TAP"TRUE"
BODY_TYPE"PLUMBING"
CDS_LIB"mstr_standard";
"B \NAC \NWC"4;
"S \NAC"
BN"0"14;
%"TAP"
"1","(-5425,3350)","2","mstr_standard","I12";
;
HDL_TAP"TRUE"
BODY_TYPE"PLUMBING"
CDS_LIB"mstr_standard";
"B \NAC \NWC"4;
"S \NAC"
BN"1"15;
%"TAP"
"1","(-5425,3400)","2","mstr_standard","I13";
;
HDL_TAP"TRUE"
BODY_TYPE"PLUMBING"
CDS_LIB"mstr_standard";
"B \NAC \NWC"4;
"S \NAC"
BN"2"16;
%"TAP"
"1","(-5425,3450)","2","mstr_standard","I14";
;
HDL_TAP"TRUE"
BODY_TYPE"PLUMBING"
CDS_LIB"mstr_standard";
"B \NAC \NWC"4;
"S \NAC"
BN"3"17;
%"TAP"
"1","(-2350,3100)","0","mstr_standard","I16";
;
HDL_TAP"TRUE"
BODY_TYPE"PLUMBING"
CDS_LIB"mstr_standard";
"B \NAC \NWC"1;
"S \NAC"
BN"1"47;
%"TAP"
"1","(-2350,3050)","0","mstr_standard","I17";
;
HDL_TAP"TRUE"
BODY_TYPE"PLUMBING"
CDS_LIB"mstr_standard";
"B \NAC \NWC"1;
"S \NAC"
BN"0"42;
%"TAP"
"1","(-2350,3200)","0","mstr_standard","I18";
;
HDL_TAP"TRUE"
BODY_TYPE"PLUMBING"
CDS_LIB"mstr_standard";
"B \NAC \NWC"1;
"S \NAC"
BN"3"49;
%"TAP"
"1","(-2350,3150)","0","mstr_standard","I19";
;
HDL_TAP"TRUE"
BODY_TYPE"PLUMBING"
CDS_LIB"mstr_standard";
"B \NAC \NWC"1;
"S \NAC"
BN"2"48;
%"TAP"
"1","(-2350,3300)","0","mstr_standard","I20";
;
HDL_TAP"TRUE"
BODY_TYPE"PLUMBING"
CDS_LIB"mstr_standard";
"B \NAC \NWC"2;
"S \NAC"
BN"0"43;
%"TAP"
"1","(-2350,3400)","0","mstr_standard","I21";
;
HDL_TAP"TRUE"
BODY_TYPE"PLUMBING"
CDS_LIB"mstr_standard";
"B \NAC \NWC"2;
"S \NAC"
BN"2"45;
%"TAP"
"1","(-2350,3350)","0","mstr_standard","I22";
;
HDL_TAP"TRUE"
BODY_TYPE"PLUMBING"
CDS_LIB"mstr_standard";
"B \NAC \NWC"2;
"S \NAC"
BN"1"44;
%"TAP"
"1","(-2350,3450)","0","mstr_standard","I23";
;
HDL_TAP"TRUE"
BODY_TYPE"PLUMBING"
CDS_LIB"mstr_standard";
"B \NAC \NWC"2;
"S \NAC"
BN"3"46;
%"VCC_CORE"
"1","(-1075,2275)","0","mstr_symbols","I60";
;
CDS_LIB"mstr_symbols"
HDL_POWER"PVCCMCP_CPU0";
"A"5;
%"SKX_EXT_B"
"9","(-3925,2550)","0","chpset_lib","I61";
;
CDS_SEC"9"
ROOM"CPU0"
CDS_LOCATION"U5D1"
SEC"9"
SEC_TYPE"BGA1"
CDS_LIB"chpset_lib"
PACK_TYPE"BGA1"
MATERIAL"IC"
PART_NUMBER"TBD"
LOCATION"U5D1";
"RSVD<172>"
$PN"BA76"36;
"RSVD<173>"
$PN"BA66"37;
"RSVD<174>"
$PN"BA64"6;
"RSVD<175>"
$PN"BA22"7;
"RSVD<176>"
$PN"BA18"8;
"RSVD<177>"
$PN"BA16"9;
"RSVD<178>"
$PN"BA14"10;
"RSVD<179>"
$PN"AY77"12;
"RSVD<180>"
$PN"AY75"13;
"RSVD<181>"
$PN"AY67"11;
"RSVD<182>"
$PN"AY65"22;
"RSVD<183>"
$PN"AW76"23;
"RSVD<184>"
$PN"AW64"38;
"RSVD<186>"
$PN"AV77"39;
"RSVD<187>"
$PN"AT25"5;
"RSVD<188>"
$PN"AT23"5;
"RSVD<189>"
$PN"AT13"40;
"RSVD<190>"
$PN"AR62"41;
"RSVD<191>"
$PN"AR26"5;
"RSVD<192>"
$PN"AR22"5;
"RSVD<193>"
$PN"AR20"5;
"DMI_TX_DP<0>"
$PN"CH5"43;
"DMI_TX_DP<1>"
$PN"CL4"44;
"DMI_TX_DP<2>"
$PN"CM3"45;
"DMI_TX_DP<3>"
$PN"CR4"46;
"DMI_TX_DN<0>"
$PN"CG4"42;
"DMI_TX_DN<1>"
$PN"CJ4"47;
"DMI_TX_DN<2>"
$PN"CN4"48;
"DMI_TX_DN<3>"
$PN"CP5"49;
"DMI_RX_DP<0>"
$PN"CL10"14;
"DMI_RX_DP<1>"
$PN"CN10"15;
"DMI_RX_DP<2>"
$PN"CP11"16;
"DMI_RX_DP<3>"
$PN"CV11"17;
"DMI_RX_DN<0>"
$PN"CK9"18;
"DMI_RX_DN<1>"
$PN"CM11"19;
"DMI_RX_DN<2>"
$PN"CR12"20;
"DMI_RX_DN<3>"
$PN"CT11"21;
"CD_TRST_N"
$PN"CD23"35;
"CD_TMS"
$PN"CE24"26;
"CD_TDO"
$PN"CC22"50;
"CD_TDI"
$PN"BY21"25;
"CD_TCLK"
$PN"CB23"24;
"CD_POR_N"
$PN"CF25"53;
"CD_PE_REFCLK_DP"
$PN"BW24"51;
"CD_PE_REFCLK_DN"
$PN"BU24"52;
"CD_HFI_REFCLK_DP"
$PN"BG16"27;
"CD_HFI_REFCLK_DN"
$PN"BE16"28;
"CD_HFI1_RESET_N"
$PN"BK23"56;
"CD_HFI1_MODPRST_N"
$PN"BT19"54;
"CD_HFI1_LED_N"
$PN"BM23"57;
"CD_HFI1_INT_N"
$PN"BM21"55;
"CD_HFI1_I2CDAT"
$PN"BH23"59;
"CD_HFI1_I2CCLK"
$PN"BJ22"58;
"CD_HFI0_RESET_N"
$PN"BN24"29;
"CD_HFI0_MODPRST_N"
$PN"BR20"30;
"CD_HFI0_LED_N"
$PN"BK21"32;
"CD_HFI0_INT_N"
$PN"BP19"31;
"CD_HFI0_I2CDAT"
$PN"BP23"34;
"CD_HFI0_I2CCLK"
$PN"BN22"33;
%"TAP"
"1","(-5425,3050)","2","mstr_standard","I7";
;
HDL_TAP"TRUE"
BODY_TYPE"PLUMBING"
CDS_LIB"mstr_standard";
"B \NAC \NWC"3;
"S \NAC"
BN"0"18;
%"TAP"
"1","(-5425,3100)","2","mstr_standard","I8";
;
HDL_TAP"TRUE"
BODY_TYPE"PLUMBING"
CDS_LIB"mstr_standard";
"B \NAC \NWC"3;
"S \NAC"
BN"1"19;
%"TAP"
"1","(-5425,3200)","2","mstr_standard","I9";
;
HDL_TAP"TRUE"
BODY_TYPE"PLUMBING"
CDS_LIB"mstr_standard";
"B \NAC \NWC"3;
"S \NAC"
BN"3"21;
END.
